# S9S_MB_2U (Grand Teton) — schematic netlist excerpt (pin names and nets, part order shuffled) for the footprints in the layout excerpt that follows; sources: Cadence DE-HDL packaged netlist, KiCad conversion of 03242023_DA0F0TMBIJ0_F0T_Motherboard_J_brd_V01_OCP.brd

R560  Q_RES  49.9 1% CHIP  pkg 0402LF  page 45 : A = SVID_ALERT1_CPU1_R_N ; B = PVNN_TERM_CPU1
R80  Q_RES  196K 1% CHIP  pkg 0402LF  page 105 : A = PD_CHD_CPU1_DIMM2_SAA ; B = GND

(kicad_pcb
	(version 20260206)
	(generator "pcbnew")
	(generator_version "10.0")
	(general
		(thickness 1.6)
		(legacy_teardrops no)
	)
	(paper "A4")
	(title_block
		(title "03242023_DA0F0TMBIJ0_F0T_Motherboard_J_brd_V01_OCP.brd")
		(comment 1 "Grand Teton / footprints 6018-6019 of 6105")
	)
	(layers
		(0 "F.Cu" signal "TOP")
		(4 "In1.Cu" signal "GND")
		(6 "In2.Cu" signal "IN1")
		(8 "In3.Cu" signal "GND1")
		(10 "In4.Cu" signal "IN2")
		(12 "In5.Cu" signal "GND2")
		(14 "In6.Cu" signal "IN3")
		(16 "In7.Cu" signal "GND3")
		(18 "In8.Cu" signal "VCC")
		(20 "In9.Cu" signal "VCC1")
		(22 "In10.Cu" signal "GND4")
		(24 "In11.Cu" signal "IN4")
		(26 "In12.Cu" signal "GND5")
		(28 "In13.Cu" signal "IN5")
		(30 "In14.Cu" signal "GND6")
		(32 "In15.Cu" signal "IN6")
		(34 "In16.Cu" signal "GND7")
		(2 "B.Cu" signal "BOTTOM")
		(9 "F.Adhes" user "F.Adhesive")
		(11 "B.Adhes" user "B.Adhesive")
		(13 "F.Paste" user "Package Geometry/Pastemask Top")
		(15 "B.Paste" user "Package Geometry/Pastemask Bottom")
		(5 "F.SilkS" user "Ref Des/Silkscreen Top")
		(7 "B.SilkS" user "Ref Des/Silkscreen Bottom")
		(1 "F.Mask" user "Board Geometry/Soldermask Top")
		(3 "B.Mask" user "Board Geometry/Soldermask Bottom")
		(17 "Dwgs.User" user "User.Drawings")
		(19 "Cmts.User" user "User.Comments")
		(21 "Eco1.User" user "User.Eco1")
		(23 "Eco2.User" user "User.Eco2")
		(25 "Edge.Cuts" user "Board Geometry/Outline")
		(27 "Margin" user)
		(31 "F.CrtYd" user "Package Geometry/Place Bound Top")
		(29 "B.CrtYd" user "Package Geometry/Place Bound Bottom")
		(35 "F.Fab" user "Ref Des/Assembly Top")
		(33 "B.Fab" user "Ref Des/Assembly Bottom")
	)
	(footprint ""
		(layer "B.Cu")
		(at 71.385684 -185.791856 90)
		(property "Reference" "R560"
			(at 0 0 90)
			(layer "B.SilkS")
			(hide yes)
			(effects
				(font
					(size 1.27 1.27)
				)
				(justify mirror)
			)
		)
		(property "Value" ""
			(at 0 0 90)
			(layer "B.Fab")
			(effects
				(font
					(size 1.27 1.27)
				)
				(justify mirror)
			)
		)
		(duplicate_pad_numbers_are_jumpers no)
		(fp_line
			(start 0.7874 -0.4064)
			(end -0.7874 -0.4064)
			(stroke
				(width 0.1524)
				(type default)
			)
			(layer "B.SilkS")
		)
		(fp_line
			(start -0.7874 -0.4064)
			(end -0.7874 0.4064)
			(stroke
				(width 0.1524)
				(type default)
			)
			(layer "B.SilkS")
		)
		(fp_line
			(start 0.7874 0.4064)
			(end 0.7874 -0.4064)
			(stroke
				(width 0.1524)
				(type default)
			)
			(layer "B.SilkS")
		)
		(fp_line
			(start -0.7874 0.4064)
			(end 0.7874 0.4064)
			(stroke
				(width 0.1524)
				(type default)
			)
			(layer "B.SilkS")
		)
		(fp_line
			(start 0.67945 -0.305054)
			(end 0.12065 -0.305054)
			(stroke
				(width 0.1)
				(type default)
			)
			(layer "B.Fab")
		)
		(fp_line
			(start 0.12065 -0.305054)
			(end 0.12065 -0.2794)
			(stroke
				(width 0.1)
				(type default)
			)
			(layer "B.Fab")
		)
		(fp_line
			(start -0.12065 -0.3048)
			(end -0.67945 -0.3048)
			(stroke
				(width 0.1)
				(type default)
			)
			(layer "B.Fab")
		)
		(fp_line
			(start -0.67945 -0.3048)
			(end -0.67945 0.3048)
			(stroke
				(width 0.1)
				(type default)
			)
			(layer "B.Fab")
		)
		(fp_line
			(start 0.12065 -0.2794)
			(end -0.12065 -0.2794)
			(stroke
				(width 0.1)
				(type default)
			)
			(layer "B.Fab")
		)
		(fp_line
			(start -0.12065 -0.2794)
			(end -0.12065 -0.3048)
			(stroke
				(width 0.1)
				(type default)
			)
			(layer "B.Fab")
		)
		(fp_line
			(start 0.12065 0.2794)
			(end 0.12065 0.3048)
			(stroke
				(width 0.1)
				(type default)
			)
			(layer "B.Fab")
		)
		(fp_line
			(start -0.120396 0.2794)
			(end 0.12065 0.2794)
			(stroke
				(width 0.1)
				(type default)
			)
			(layer "B.Fab")
		)
		(fp_line
			(start 0.67945 0.3048)
			(end 0.67945 -0.305054)
			(stroke
				(width 0.1)
				(type default)
			)
			(layer "B.Fab")
		)
		(fp_line
			(start 0.12065 0.3048)
			(end 0.67945 0.3048)
			(stroke
				(width 0.1)
				(type default)
			)
			(layer "B.Fab")
		)
		(fp_line
			(start -0.120396 0.3048)
			(end -0.120396 0.2794)
			(stroke
				(width 0.1)
				(type default)
			)
			(layer "B.Fab")
		)
		(fp_line
			(start -0.67945 0.3048)
			(end -0.120396 0.3048)
			(stroke
				(width 0.1)
				(type default)
			)
			(layer "B.Fab")
		)
		(pad "1" smd circle
			(at 0.40005 0 270)
			(size 0 0)
			(layers "B.Cu" "B.Mask" "B.Paste")
			(net "SVID_ALERT1_CPU1_R_N")
		)
		(pad "2" smd circle
			(at -0.40005 0 270)
			(size 0 0)
			(layers "B.Cu" "B.Mask" "B.Paste")
			(net "PVNN_TERM_CPU1")
		)
	)
	(footprint ""
		(layer "B.Cu")
		(at 17.596358 -318.666622)
		(property "Reference" "R80"
			(at 0 0 0)
			(layer "B.SilkS")
			(hide yes)
			(effects
				(font
					(size 1.27 1.27)
				)
				(justify mirror)
			)
		)
		(property "Value" ""
			(at 0 0 0)
			(layer "B.Fab")
			(effects
				(font
					(size 1.27 1.27)
				)
				(justify mirror)
			)
		)
		(duplicate_pad_numbers_are_jumpers no)
		(fp_line
			(start -0.7874 -0.4064)
			(end -0.7874 0.4064)
			(stroke
				(width 0.1524)
				(type default)
			)
			(layer "B.SilkS")
		)
		(fp_line
			(start -0.7874 0.4064)
			(end 0.7874 0.4064)
			(stroke
				(width 0.1524)
				(type default)
			)
			(layer "B.SilkS")
		)
		(fp_line
			(start 0.7874 -0.4064)
			(end -0.7874 -0.4064)
			(stroke
				(width 0.1524)
				(type default)
			)
			(layer "B.SilkS")
		)
		(fp_line
			(start 0.7874 0.4064)
			(end 0.7874 -0.4064)
			(stroke
				(width 0.1524)
				(type default)
			)
			(layer "B.SilkS")
		)
		(fp_line
			(start -0.67945 -0.3048)
			(end -0.67945 0.3048)
			(stroke
				(width 0.1)
				(type default)
			)
			(layer "B.Fab")
		)
		(fp_line
			(start -0.67945 0.3048)
			(end -0.120396 0.3048)
			(stroke
				(width 0.1)
				(type default)
			)
			(layer "B.Fab")
		)
		(fp_line
			(start -0.12065 -0.3048)
			(end -0.67945 -0.3048)
			(stroke
				(width 0.1)
				(type default)
			)
			(layer "B.Fab")
		)
		(fp_line
			(start -0.12065 -0.2794)
			(end -0.12065 -0.3048)
			(stroke
				(width 0.1)
				(type default)
			)
			(layer "B.Fab")
		)
		(fp_line
			(start -0.120396 0.2794)
			(end 0.12065 0.2794)
			(stroke
				(width 0.1)
				(type default)
			)
			(layer "B.Fab")
		)
		(fp_line
			(start -0.120396 0.3048)
			(end -0.120396 0.2794)
			(stroke
				(width 0.1)
				(type default)
			)
			(layer "B.Fab")
		)
		(fp_line
			(start 0.12065 -0.305054)
			(end 0.12065 -0.2794)
			(stroke
				(width 0.1)
				(type default)
			)
			(layer "B.Fab")
		)
		(fp_line
			(start 0.12065 -0.2794)
			(end -0.12065 -0.2794)
			(stroke
				(width 0.1)
				(type default)
			)
			(layer "B.Fab")
		)
		(fp_line
			(start 0.12065 0.2794)
			(end 0.12065 0.3048)
			(stroke
				(width 0.1)
				(type default)
			)
			(layer "B.Fab")
		)
		(fp_line
			(start 0.12065 0.3048)
			(end 0.67945 0.3048)
			(stroke
				(width 0.1)
				(type default)
			)
			(layer "B.Fab")
		)
		(fp_line
			(start 0.67945 -0.305054)
			(end 0.12065 -0.305054)
			(stroke
				(width 0.1)
				(type default)
			)
			(layer "B.Fab")
		)
		(fp_line
			(start 0.67945 0.3048)
			(end 0.67945 -0.305054)
			(stroke
				(width 0.1)
				(type default)
			)
			(layer "B.Fab")
		)
		(pad "1" smd circle
			(at 0.40005 0 180)
			(size 0 0)
			(layers "B.Cu" "B.Mask" "B.Paste")
			(net "PD_CHD_CPU1_DIMM2_SAA")
		)
		(pad "2" smd circle
			(at -0.40005 0 180)
			(size 0 0)
			(layers "B.Cu" "B.Mask" "B.Paste")
			(net "GND")
		)
	)
)
